(kicad_pcb
	(version 20241229)
	(generator "pcbnew")
	(generator_version "9.0")
	(general
		(thickness 1.6296)
		(legacy_teardrops no)
	)
	(paper "A3")
	(title_block
		(title "Thunderbolt to 10GbE adapter")
		(date "2026-04-21")
		(rev "1.1.0")
		(company "Antmicro Ltd")
		(comment 1 "www.antmicro.com")
		(comment 9 "footprints 343-347 of 703")
	)
	(layers
		(0 "F.Cu" signal)
		(4 "In1.Cu" signal)
		(6 "In2.Cu" signal)
		(8 "In3.Cu" signal)
		(10 "In4.Cu" signal)
		(12 "In5.Cu" signal)
		(14 "In6.Cu" signal)
		(2 "B.Cu" signal)
		(9 "F.Adhes" user "F.Adhesive")
		(11 "B.Adhes" user "B.Adhesive")
		(13 "F.Paste" user)
		(15 "B.Paste" user)
		(5 "F.SilkS" user "F.Silkscreen")
		(7 "B.SilkS" user "B.Silkscreen")
		(1 "F.Mask" user)
		(3 "B.Mask" user)
		(17 "Dwgs.User" user "User.Drawings")
		(19 "Cmts.User" user "User.Comments")
		(21 "Eco1.User" user "User.Eco1")
		(23 "Eco2.User" user "User.Eco2")
		(25 "Edge.Cuts" user)
		(27 "Margin" user)
		(31 "F.CrtYd" user "F.Courtyard")
		(29 "B.CrtYd" user "B.Courtyard")
		(35 "F.Fab" user)
		(33 "B.Fab" user)
	)
	(footprint "antmicro-footprints:L_Bourns-SRP4021HMT"
		(layer "F.Cu")
		(at 145.405 66.925 -90)
		(property "Reference" "L11"
			(at -12.424999 -21.944998 270)
			(layer "F.SilkS")
			(effects
				(font
					(size 0.7 0.7)
					(thickness 0.15)
				)
			)
		)
		(property "Value" "L_1u_10A_Bourns-SRP4021HMT"
			(at -2.85 3.4 270)
			(layer "F.Fab")
			(effects
				(font
					(size 0.7 0.7)
					(thickness 0.15)
				)
				(justify left bottom)
			)
		)
		(property "Datasheet" "https://www.mouser.com/datasheet/2/54/Bourns_04_01_2025_SRP4021HMT_Datasheet-3580094.pdf"
			(at 0 0 270)
			(layer "F.Fab")
			(effects
				(font
					(size 0.7 0.7)
					(thickness 0.15)
				)
				(justify left bottom)
			)
		)
		(property "Description" "Power Inductors - SMD Ind,4.1x4.2x1.9mm,1uH+/-20%,10A, Shielded"
			(at 0 0 270)
			(layer "F.Fab")
			(effects
				(font
					(size 0.7 0.7)
					(thickness 0.15)
				)
				(justify left bottom)
			)
		)
		(property "Val" "1u/10A"
			(at 0 0 270)
			(unlocked yes)
			(layer "F.Fab")
			(hide yes)
			(effects
				(font
					(size 1 1)
					(thickness 0.15)
				)
			)
		)
		(property "Manufacturer" "Bourns"
			(at 0 0 270)
			(unlocked yes)
			(layer "F.Fab")
			(hide yes)
			(effects
				(font
					(size 1 1)
					(thickness 0.15)
				)
			)
		)
		(property "MPN" "SRP4021HMT-1R0M"
			(at 0 0 270)
			(unlocked yes)
			(layer "F.Fab")
			(hide yes)
			(effects
				(font
					(size 1 1)
					(thickness 0.15)
				)
			)
		)
		(property "ISat" ""
			(at 0 0 270)
			(unlocked yes)
			(layer "F.Fab")
			(hide yes)
			(effects
				(font
					(size 1 1)
					(thickness 0.15)
				)
			)
		)
		(property "Isat" "8A"
			(at 0 0 270)
			(unlocked yes)
			(layer "F.Fab")
			(hide yes)
			(effects
				(font
					(size 1 1)
					(thickness 0.15)
				)
			)
		)
		(property "IMax" ""
			(at 0 0 270)
			(unlocked yes)
			(layer "F.Fab")
			(hide yes)
			(effects
				(font
					(size 1 1)
					(thickness 0.15)
				)
			)
		)
		(property "Imax" "10A"
			(at 0 0 270)
			(unlocked yes)
			(layer "F.Fab")
			(hide yes)
			(effects
				(font
					(size 1 1)
					(thickness 0.15)
				)
			)
		)
		(property "Size" "4.2x4.1"
			(at 0 0 270)
			(unlocked yes)
			(layer "F.Fab")
			(hide yes)
			(effects
				(font
					(size 1 1)
					(thickness 0.15)
				)
			)
		)
		(property "Author" "Antmicro"
			(at 0 0 270)
			(unlocked yes)
			(layer "F.Fab")
			(hide yes)
			(effects
				(font
					(size 1 1)
					(thickness 0.15)
				)
			)
		)
		(property "License" "Apache-2.0"
			(at 0 0 270)
			(unlocked yes)
			(layer "F.Fab")
			(hide yes)
			(effects
				(font
					(size 1 1)
					(thickness 0.15)
				)
			)
		)
		(sheetname "/X710-AT2 power/")
		(sheetfile "x710-at2-power.kicad_sch")
		(attr smd)
		(fp_line
			(start -0.8 2.05)
			(end 0.8 2.05)
			(stroke
				(width 0.15)
				(type solid)
			)
			(layer "F.SilkS")
		)
		(fp_line
			(start -0.8 -2.05)
			(end 0.8 -2.05)
			(stroke
				(width 0.15)
				(type solid)
			)
			(layer "F.SilkS")
		)
		(fp_rect
			(start -2.85 -2.3)
			(end 2.85 2.3)
			(stroke
				(width 0.05)
				(type solid)
			)
			(fill no)
			(layer "F.CrtYd")
		)
		(fp_rect
			(start -2 -2.05)
			(end 2 2.05)
			(stroke
				(width 0.15)
				(type solid)
			)
			(fill no)
			(layer "F.Fab")
		)
		(fp_text user "${REFERENCE}"
			(at -2.85 5.8 270)
			(layer "F.Fab")
			(effects
				(font
					(size 0.7 0.7)
					(thickness 0.15)
				)
				(justify left bottom)
			)
		)
		(fp_text user "License: Apache-2.0"
			(at -2.85 7 270)
			(layer "F.Fab")
			(effects
				(font
					(size 0.7 0.7)
					(thickness 0.15)
				)
				(justify left bottom)
			)
		)
		(fp_text user "Author: Antmicro"
			(at -2.85 4.6 270)
			(layer "F.Fab")
			(effects
				(font
					(size 0.7 0.7)
					(thickness 0.15)
				)
				(justify left bottom)
			)
		)
		(pad "1" smd rect
			(at 1.85 0 90)
			(size 1.5 3.5)
			(layers "F.Cu" "F.Mask" "F.Paste")
			(net 427 "Net-(U14H-SVR_IND)")
			(pintype "passive")
		)
		(pad "2" smd rect
			(at -1.85 0 90)
			(size 1.5 3.5)
			(layers "F.Cu" "F.Mask" "F.Paste")
			(net 1 "VCCA")
			(pintype "passive")
		)
	)
	(footprint "antmicro-footprints:R_0402_1005Metric"
		(layer "F.Cu")
		(at 154.305 69.074999 -90)
		(descr "Resistor SMD 0402")
		(tags "resistor SMD 0402")
		(property "Reference" "R155"
			(at -11.574999 -20.295 270)
			(layer "F.SilkS")
			(effects
				(font
					(size 0.7 0.7)
					(thickness 0.15)
				)
			)
		)
		(property "Value" "R_100R_0402"
			(at -1.011843 1.772047 270)
			(layer "F.Fab")
			(effects
				(font
					(size 0.7 0.7)
					(thickness 0.15)
				)
				(justify left bottom)
			)
		)
		(property "Datasheet" "https://www.bourns.com/docs/product-datasheets/cr.pdf"
			(at 0 0 270)
			(layer "F.Fab")
			(hide yes)
			(effects
				(font
					(size 1.27 1.27)
					(thickness 0.15)
				)
			)
		)
		(property "Description" "SMD Chip Resistor, 100 ohm, ± 1%, 62.5 mW, 0402 [1005 Metric], Thick Film, General Purpose"
			(at 0 0 270)
			(layer "F.Fab")
			(hide yes)
			(effects
				(font
					(size 1.27 1.27)
					(thickness 0.15)
				)
			)
		)
		(property "MPN" "CR0402-FX-1000GLF"
			(at 0 0 270)
			(unlocked yes)
			(layer "F.Fab")
			(hide yes)
			(effects
				(font
					(size 1 1)
					(thickness 0.15)
				)
			)
		)
		(property "Manufacturer" "Bourns"
			(at 0 0 270)
			(unlocked yes)
			(layer "F.Fab")
			(hide yes)
			(effects
				(font
					(size 1 1)
					(thickness 0.15)
				)
			)
		)
		(property "License" "Apache-2.0"
			(at 0 0 270)
			(unlocked yes)
			(layer "F.Fab")
			(hide yes)
			(effects
				(font
					(size 1 1)
					(thickness 0.15)
				)
			)
		)
		(property "Author" "Antmicro"
			(at 0 0 270)
			(unlocked yes)
			(layer "F.Fab")
			(hide yes)
			(effects
				(font
					(size 1 1)
					(thickness 0.15)
				)
			)
		)
		(property "Val" "100R"
			(at 0 0 270)
			(unlocked yes)
			(layer "F.Fab")
			(hide yes)
			(effects
				(font
					(size 1 1)
					(thickness 0.15)
				)
			)
		)
		(property "Tolerance" "1%"
			(at 0 0 270)
			(unlocked yes)
			(layer "F.Fab")
			(hide yes)
			(effects
				(font
					(size 1 1)
					(thickness 0.15)
				)
			)
		)
		(sheetname "/X710-AT2 Misc/")
		(sheetfile "x710-at2-mics.kicad_sch")
		(attr smd dnp)
		(fp_rect
			(start -0.925 -0.47)
			(end 0.925 0.47)
			(stroke
				(width 0.05)
				(type default)
			)
			(fill no)
			(layer "F.CrtYd")
		)
		(fp_rect
			(start -0.5 -0.25)
			(end 0.5 0.25)
			(stroke
				(width 0.15)
				(type solid)
			)
			(fill no)
			(layer "F.Fab")
		)
		(fp_text user "Author: Antmicro"
			(at -0.95 4.169 270)
			(layer "F.Fab")
			(effects
				(font
					(size 0.7 0.7)
					(thickness 0.15)
				)
				(justify left bottom)
			)
		)
		(fp_text user "${REFERENCE}"
			(at -0.95 3.168 270)
			(layer "F.Fab")
			(effects
				(font
					(size 0.7 0.7)
					(thickness 0.15)
				)
				(justify left bottom)
			)
		)
		(fp_text user "License: Apache-2.0"
			(at -0.95 5.169 270)
			(layer "F.Fab")
			(effects
				(font
					(size 0.7 0.7)
					(thickness 0.15)
				)
				(justify left bottom)
			)
		)
		(pad "1" smd roundrect
			(at -0.48 0 270)
			(size 0.59 0.64)
			(layers "F.Cu" "F.Mask" "F.Paste")
			(roundrect_rratio 0.25)
			(net 23 "GND")
			(pintype "passive")
		)
		(pad "2" smd roundrect
			(at 0.48 0 270)
			(size 0.59 0.64)
			(layers "F.Cu" "F.Mask" "F.Paste")
			(roundrect_rratio 0.25)
			(net 75 "/X710-AT2 Misc/AUX_PWR")
			(pintype "passive")
		)
	)
	(footprint "antmicro-footprints:R_0402_1005Metric"
		(layer "F.Cu")
		(at 129.52 93.2)
		(descr "Resistor SMD 0402")
		(tags "resistor SMD 0402")
		(property "Reference" "R98"
			(at 38.914999 -9.199999 0)
			(layer "F.SilkS")
			(effects
				(font
					(size 0.7 0.7)
					(thickness 0.15)
				)
			)
		)
		(property "Value" "R_90k9_0402"
			(at -1.011843 1.772047 0)
			(layer "F.Fab")
			(effects
				(font
					(size 0.7 0.7)
					(thickness 0.15)
				)
				(justify left bottom)
			)
		)
		(property "Datasheet" "https://www.bourns.com/docs/product-datasheets/cr.pdf"
			(at 0 0 0)
			(layer "F.Fab")
			(hide yes)
			(effects
				(font
					(size 1.27 1.27)
					(thickness 0.15)
				)
			)
		)
		(property "Description" "SMD Chip Resistor"
			(at 0 0 0)
			(layer "F.Fab")
			(hide yes)
			(effects
				(font
					(size 1.27 1.27)
					(thickness 0.15)
				)
			)
		)
		(property "MPN" "CR0402-FX-9092GLF"
			(at 0 0 0)
			(unlocked yes)
			(layer "F.Fab")
			(hide yes)
			(effects
				(font
					(size 1 1)
					(thickness 0.15)
				)
			)
		)
		(property "Manufacturer" "Bourns"
			(at 0 0 0)
			(unlocked yes)
			(layer "F.Fab")
			(hide yes)
			(effects
				(font
					(size 1 1)
					(thickness 0.15)
				)
			)
		)
		(property "License" "Apache-2.0"
			(at 0 0 0)
			(unlocked yes)
			(layer "F.Fab")
			(hide yes)
			(effects
				(font
					(size 1 1)
					(thickness 0.15)
				)
			)
		)
		(property "Author" "Antmicro"
			(at 0 0 0)
			(unlocked yes)
			(layer "F.Fab")
			(hide yes)
			(effects
				(font
					(size 1 1)
					(thickness 0.15)
				)
			)
		)
		(property "Val" "90k9"
			(at 0 0 0)
			(unlocked yes)
			(layer "F.Fab")
			(hide yes)
			(effects
				(font
					(size 1 1)
					(thickness 0.15)
				)
			)
		)
		(property "Tolerance" "1%"
			(at 0 0 0)
			(unlocked yes)
			(layer "F.Fab")
			(hide yes)
			(effects
				(font
					(size 1 1)
					(thickness 0.15)
				)
			)
		)
		(sheetname "/X710 DCDC converters/")
		(sheetfile "DCDC_converters_X710.kicad_sch")
		(attr smd)
		(fp_rect
			(start -0.925 -0.47)
			(end 0.925 0.47)
			(stroke
				(width 0.05)
				(type default)
			)
			(fill no)
			(layer "F.CrtYd")
		)
		(fp_rect
			(start -0.5 -0.25)
			(end 0.5 0.25)
			(stroke
				(width 0.15)
				(type solid)
			)
			(fill no)
			(layer "F.Fab")
		)
		(fp_text user "License: Apache-2.0"
			(at -0.95 5.169 0)
			(layer "F.Fab")
			(effects
				(font
					(size 0.7 0.7)
					(thickness 0.15)
				)
				(justify left bottom)
			)
		)
		(fp_text user "Author: Antmicro"
			(at -0.95 4.169 0)
			(layer "F.Fab")
			(effects
				(font
					(size 0.7 0.7)
					(thickness 0.15)
				)
				(justify left bottom)
			)
		)
		(fp_text user "${REFERENCE}"
			(at -0.95 3.168 0)
			(layer "F.Fab")
			(effects
				(font
					(size 0.7 0.7)
					(thickness 0.15)
				)
				(justify left bottom)
			)
		)
		(pad "1" smd roundrect
			(at -0.48 0)
			(size 0.59 0.64)
			(layers "F.Cu" "F.Mask" "F.Paste")
			(roundrect_rratio 0.25)
			(net 333 "/X710 DCDC converters/3V3_FB")
			(pintype "passive")
		)
		(pad "2" smd roundrect
			(at 0.48 0)
			(size 0.59 0.64)
			(layers "F.Cu" "F.Mask" "F.Paste")
			(roundrect_rratio 0.25)
			(net 334 "/X710 DCDC converters/+3V3_OUT")
			(pintype "passive")
		)
	)
	(footprint "antmicro-footprints:C_0402_1005Metric"
		(layer "F.Cu")
		(at 159.105 69.075 90)
		(descr "Capacitor SMD 0402")
		(tags "capacitor SMD 0402")
		(property "Reference" "C287"
			(at 11.574999 20.295 90)
			(layer "F.SilkS")
			(effects
				(font
					(size 0.7 0.7)
					(thickness 0.15)
				)
			)
		)
		(property "Value" "C_100n_0402"
			(at -1.022927 2.155213 90)
			(layer "F.Fab")
			(effects
				(font
					(size 0.7 0.7)
					(thickness 0.15)
				)
				(justify left bottom)
			)
		)
		(property "Datasheet" "https://www.murata.com/products/productdetail?partno=GRM155R61H104KE14%23"
			(at 0 0 90)
			(layer "F.Fab")
			(hide yes)
			(effects
				(font
					(size 1.27 1.27)
					(thickness 0.15)
				)
			)
		)
		(property "Description" "SMD Multilayer Ceramic Capacitor, 0.1 µF, 50 V, 0402 [1005 Metric], ± 10%, X5R, GRM Series"
			(at 0 0 90)
			(layer "F.Fab")
			(hide yes)
			(effects
				(font
					(size 1.27 1.27)
					(thickness 0.15)
				)
			)
		)
		(property "MPN" "GRM155R61H104KE14D"
			(at 0 0 90)
			(unlocked yes)
			(layer "F.Fab")
			(hide yes)
			(effects
				(font
					(size 1 1)
					(thickness 0.15)
				)
			)
		)
		(property "Val" "100n"
			(at 0 0 90)
			(unlocked yes)
			(layer "F.Fab")
			(hide yes)
			(effects
				(font
					(size 1 1)
					(thickness 0.15)
				)
			)
		)
		(property "Voltage" "50V"
			(at 0 0 90)
			(unlocked yes)
			(layer "F.Fab")
			(hide yes)
			(effects
				(font
					(size 1 1)
					(thickness 0.15)
				)
			)
		)
		(property "Dielectric" "X5R"
			(at 0 0 90)
			(unlocked yes)
			(layer "F.Fab")
			(hide yes)
			(effects
				(font
					(size 1 1)
					(thickness 0.15)
				)
			)
		)
		(property "Manufacturer" "Murata"
			(at 0 0 90)
			(unlocked yes)
			(layer "F.Fab")
			(hide yes)
			(effects
				(font
					(size 1 1)
					(thickness 0.15)
				)
			)
		)
		(property "License" "Apache-2.0"
			(at 0 0 90)
			(unlocked yes)
			(layer "F.Fab")
			(hide yes)
			(effects
				(font
					(size 1 1)
					(thickness 0.15)
				)
			)
		)
		(property "Author" "Antmicro"
			(at 0 0 90)
			(unlocked yes)
			(layer "F.Fab")
			(hide yes)
			(effects
				(font
					(size 1 1)
					(thickness 0.15)
				)
			)
		)
		(sheetname "/X710-AT2 10GbE/")
		(sheetfile "x710-at2-10gbe.kicad_sch")
		(attr smd)
		(fp_rect
			(start -0.925 -0.47)
			(end 0.925 0.47)
			(stroke
				(width 0.05)
				(type default)
			)
			(fill no)
			(layer "F.CrtYd")
		)
		(fp_line
			(start 0.504 -0.25)
			(end 0.504 0.248)
			(stroke
				(width 0.15)
				(type solid)
			)
			(layer "F.Fab")
		)
		(fp_line
			(start -0.494 -0.25)
			(end 0.504 -0.25)
			(stroke
				(width 0.15)
				(type solid)
			)
			(layer "F.Fab")
		)
		(fp_line
			(start 0.504 0.248)
			(end -0.494 0.248)
			(stroke
				(width 0.15)
				(type solid)
			)
			(layer "F.Fab")
		)
		(fp_line
			(start -0.494 0.248)
			(end -0.494 -0.25)
			(stroke
				(width 0.15)
				(type solid)
			)
			(layer "F.Fab")
		)
		(fp_text user "License: Apache-2.0"
			(at -0.939 5.799 90)
			(layer "F.Fab")
			(effects
				(font
					(size 0.7 0.7)
					(thickness 0.15)
				)
				(justify left bottom)
			)
		)
		(fp_text user "${REFERENCE}"
			(at -0.939 4.599 90)
			(layer "F.Fab")
			(effects
				(font
					(size 0.7 0.7)
					(thickness 0.15)
				)
				(justify left bottom)
			)
		)
		(fp_text user "Author: Antmicro"
			(at -0.939 3.399 90)
			(layer "F.Fab")
			(effects
				(font
					(size 0.7 0.7)
					(thickness 0.15)
				)
				(justify left bottom)
			)
		)
		(pad "1" smd roundrect
			(at -0.48 0 90)
			(size 0.59 0.64)
			(layers "F.Cu" "F.Mask" "F.Paste")
			(roundrect_rratio 0.25)
			(net 24 "/X710-AT2 10GbE/25MHZ_OSC.+")
			(pintype "passive")
		)
		(pad "2" smd roundrect
			(at 0.48 0 90)
			(size 0.59 0.64)
			(layers "F.Cu" "F.Mask" "F.Paste")
			(roundrect_rratio 0.25)
			(net 25 "/X710-AT2 10GbE/25MHZ_OSC_AC.+")
			(pintype "passive")
		)
	)
	(footprint "antmicro-footprints:C_0402_1005Metric"
		(layer "F.Cu")
		(at 117.8 125 180)
		(descr "Capacitor SMD 0402")
		(tags "capacitor SMD 0402")
		(property "Reference" "C50"
			(at -0.8 -0.2 180)
			(layer "F.SilkS")
			(effects
				(font
					(size 0.7 0.7)
					(thickness 0.15)
				)
				(justify left bottom)
			)
		)
		(property "Value" "C_220n_0402"
			(at -1.022927 2.155213 180)
			(layer "F.Fab")
			(effects
				(font
					(size 0.7 0.7)
					(thickness 0.15)
				)
				(justify left bottom)
			)
		)
		(property "Datasheet" "https://www.yageo.com/en/Chart/Download/pdf/CC0402KRX5R6BB224"
			(at 0 0 180)
			(layer "F.Fab")
			(hide yes)
			(effects
				(font
					(size 1.27 1.27)
					(thickness 0.15)
				)
			)
		)
		(property "Description" "SMD Multilayer Ceramic Capacitor, 0.22 µF, 10 V, 0402 [1005 Metric], ± 10%, X5R, CC Series"
			(at 0 0 180)
			(layer "F.Fab")
			(hide yes)
			(effects
				(font
					(size 1.27 1.27)
					(thickness 0.15)
				)
			)
		)
		(property "MPN" "CC0402KRX5R6BB224"
			(at 0 0 180)
			(unlocked yes)
			(layer "F.Fab")
			(hide yes)
			(effects
				(font
					(size 1 1)
					(thickness 0.15)
				)
			)
		)
		(property "Manufacturer" "YAGEO"
			(at 0 0 180)
			(unlocked yes)
			(layer "F.Fab")
			(hide yes)
			(effects
				(font
					(size 1 1)
					(thickness 0.15)
				)
			)
		)
		(property "License" "Apache-2.0"
			(at 0 0 180)
			(unlocked yes)
			(layer "F.Fab")
			(hide yes)
			(effects
				(font
					(size 1 1)
					(thickness 0.15)
				)
			)
		)
		(property "Val" "220n"
			(at 0 0 180)
			(unlocked yes)
			(layer "F.Fab")
			(hide yes)
			(effects
				(font
					(size 1 1)
					(thickness 0.15)
				)
			)
		)
		(property "Voltage" ""
			(at 0 0 180)
			(unlocked yes)
			(layer "F.Fab")
			(hide yes)
			(effects
				(font
					(size 1 1)
					(thickness 0.15)
				)
			)
		)
		(property "Dielectric" ""
			(at 0 0 180)
			(unlocked yes)
			(layer "F.Fab")
			(hide yes)
			(effects
				(font
					(size 1 1)
					(thickness 0.15)
				)
			)
		)
		(property "Author" "Antmicro"
			(at 0 0 180)
			(unlocked yes)
			(layer "F.Fab")
			(hide yes)
			(effects
				(font
					(size 1 1)
					(thickness 0.15)
				)
			)
		)
		(sheetname "/TB Controller/")
		(sheetfile "tb.kicad_sch")
		(attr smd)
		(fp_rect
			(start -0.925 -0.47)
			(end 0.925 0.47)
			(stroke
				(width 0.05)
				(type default)
			)
			(fill no)
			(layer "F.CrtYd")
		)
		(fp_line
			(start 0.504 0.248)
			(end -0.494 0.248)
			(stroke
				(width 0.15)
				(type solid)
			)
			(layer "F.Fab")
		)
		(fp_line
			(start 0.504 -0.25)
			(end 0.504 0.248)
			(stroke
				(width 0.15)
				(type solid)
			)
			(layer "F.Fab")
		)
		(fp_line
			(start -0.494 0.248)
			(end -0.494 -0.25)
			(stroke
				(width 0.15)
				(type solid)
			)
			(layer "F.Fab")
		)
		(fp_line
			(start -0.494 -0.25)
			(end 0.504 -0.25)
			(stroke
				(width 0.15)
				(type solid)
			)
			(layer "F.Fab")
		)
		(fp_text user "License: Apache-2.0"
			(at -0.939 5.799 180)
			(layer "F.Fab")
			(effects
				(font
					(size 0.7 0.7)
					(thickness 0.15)
				)
				(justify left bottom)
			)
		)
		(fp_text user "Author: Antmicro"
			(at -0.939 3.399 180)
			(layer "F.Fab")
			(effects
				(font
					(size 0.7 0.7)
					(thickness 0.15)
				)
				(justify left bottom)
			)
		)
		(fp_text user "${REFERENCE}"
			(at -0.939 4.599 180)
			(layer "F.Fab")
			(effects
				(font
					(size 0.7 0.7)
					(thickness 0.15)
				)
				(justify left bottom)
			)
		)
		(pad "1" smd roundrect
			(at -0.48 0 180)
			(size 0.59 0.64)
			(layers "F.Cu" "F.Mask" "F.Paste")
			(roundrect_rratio 0.25)
			(net 318 "/TB Controller/TB_PCIE_TX2_N")
			(pintype "passive")
		)
		(pad "2" smd roundrect
			(at 0.48 0 180)
			(size 0.59 0.64)
			(layers "F.Cu" "F.Mask" "F.Paste")
			(roundrect_rratio 0.25)
			(net 326 "/TB Controller/PCIex4.RX2-")
			(pintype "passive")
		)
	)
)
